(kicad_pcb
	(version 20260206)
	(generator "pcbnew")
	(generator_version "10.0")
	(general
		(thickness 1.6)
		(legacy_teardrops no)
	)
	(paper "A4")
	(title_block
		(title "12092022_DA0F0TFB6D0_F0T_FAN_BOARD_MP5048_D_brd_v02_OCP.brd")
		(comment 1 "Grand Teton / footprints 869-871 of 924")
	)
	(layers
		(0 "F.Cu" signal "TOP")
		(4 "In1.Cu" signal "GND")
		(6 "In2.Cu" signal "IN1")
		(8 "In3.Cu" signal "IN2")
		(10 "In4.Cu" signal "GND1")
		(2 "B.Cu" signal "BOTTOM")
		(9 "F.Adhes" user "F.Adhesive")
		(11 "B.Adhes" user "B.Adhesive")
		(13 "F.Paste" user "Package Geometry/Pastemask Top")
		(15 "B.Paste" user "Package Geometry/Pastemask Bottom")
		(5 "F.SilkS" user "Ref Des/Silkscreen Top")
		(7 "B.SilkS" user "Ref Des/Silkscreen Bottom")
		(1 "F.Mask" user "Board Geometry/Soldermask Top")
		(3 "B.Mask" user "Board Geometry/Soldermask Bottom")
		(17 "Dwgs.User" user "User.Drawings")
		(19 "Cmts.User" user "User.Comments")
		(21 "Eco1.User" user "User.Eco1")
		(23 "Eco2.User" user "User.Eco2")
		(25 "Edge.Cuts" user "Board Geometry/Outline")
		(27 "Margin" user)
		(31 "F.CrtYd" user "Package Geometry/Place Bound Top")
		(29 "B.CrtYd" user "Package Geometry/Place Bound Bottom")
		(35 "F.Fab" user "Ref Des/Assembly Top")
		(33 "B.Fab" user "Ref Des/Assembly Bottom")
	)
	(footprint ""
		(layer "B.Cu")
		(at 44.45 -73.971912 90)
		(property "Reference" "PC34"
			(at 0 0 90)
			(layer "B.SilkS")
			(hide yes)
			(effects
				(font
					(size 1.27 1.27)
				)
				(justify mirror)
			)
		)
		(property "Value" ""
			(at 0 0 90)
			(layer "B.Fab")
			(effects
				(font
					(size 1.27 1.27)
				)
				(justify mirror)
			)
		)
		(duplicate_pad_numbers_are_jumpers no)
		(fp_line
			(start 0.7874 -0.4064)
			(end -0.7874 -0.4064)
			(stroke
				(width 0.1524)
				(type default)
			)
			(layer "B.SilkS")
		)
		(fp_line
			(start -0.7874 -0.4064)
			(end -0.7874 0.4064)
			(stroke
				(width 0.1524)
				(type default)
			)
			(layer "B.SilkS")
		)
		(fp_line
			(start 0.7874 0.4064)
			(end 0.7874 -0.4064)
			(stroke
				(width 0.1524)
				(type default)
			)
			(layer "B.SilkS")
		)
		(fp_line
			(start -0.7874 0.4064)
			(end 0.7874 0.4064)
			(stroke
				(width 0.1524)
				(type default)
			)
			(layer "B.SilkS")
		)
		(fp_line
			(start 0.67945 -0.305054)
			(end 0.12065 -0.305054)
			(stroke
				(width 0.1)
				(type default)
			)
			(layer "B.Fab")
		)
		(fp_line
			(start 0.12065 -0.305054)
			(end 0.12065 -0.2794)
			(stroke
				(width 0.1)
				(type default)
			)
			(layer "B.Fab")
		)
		(fp_line
			(start -0.12065 -0.3048)
			(end -0.67945 -0.3048)
			(stroke
				(width 0.1)
				(type default)
			)
			(layer "B.Fab")
		)
		(fp_line
			(start -0.67945 -0.3048)
			(end -0.67945 0.3048)
			(stroke
				(width 0.1)
				(type default)
			)
			(layer "B.Fab")
		)
		(fp_line
			(start 0.12065 -0.2794)
			(end -0.12065 -0.2794)
			(stroke
				(width 0.1)
				(type default)
			)
			(layer "B.Fab")
		)
		(fp_line
			(start -0.12065 -0.2794)
			(end -0.12065 -0.3048)
			(stroke
				(width 0.1)
				(type default)
			)
			(layer "B.Fab")
		)
		(fp_line
			(start 0.12065 0.2794)
			(end 0.12065 0.3048)
			(stroke
				(width 0.1)
				(type default)
			)
			(layer "B.Fab")
		)
		(fp_line
			(start -0.120396 0.2794)
			(end 0.12065 0.2794)
			(stroke
				(width 0.1)
				(type default)
			)
			(layer "B.Fab")
		)
		(fp_line
			(start 0.67945 0.3048)
			(end 0.67945 -0.305054)
			(stroke
				(width 0.1)
				(type default)
			)
			(layer "B.Fab")
		)
		(fp_line
			(start 0.12065 0.3048)
			(end 0.67945 0.3048)
			(stroke
				(width 0.1)
				(type default)
			)
			(layer "B.Fab")
		)
		(fp_line
			(start -0.120396 0.3048)
			(end -0.120396 0.2794)
			(stroke
				(width 0.1)
				(type default)
			)
			(layer "B.Fab")
		)
		(fp_line
			(start -0.67945 0.3048)
			(end -0.120396 0.3048)
			(stroke
				(width 0.1)
				(type default)
			)
			(layer "B.Fab")
		)
		(pad "1" smd circle
			(at 0.40005 0 270)
			(size 0 0)
			(layers "B.Cu" "B.Mask" "B.Paste")
			(net "FAN_2_TIMER")
		)
		(pad "2" smd circle
			(at -0.40005 0 270)
			(size 0 0)
			(layers "B.Cu" "B.Mask" "B.Paste")
			(net "GND")
		)
	)
	(footprint ""
		(layer "B.Cu")
		(at 5.900166 -243.595144)
		(property "Reference" "PU8"
			(at 3.789934 4.315714 0)
			(unlocked yes)
			(layer "B.SilkS")
			(effects
				(font
					(size 0.7874 0.5842)
					(thickness 0.1524)
				)
				(justify left mirror)
			)
		)
		(property "Value" ""
			(at 0 0 0)
			(layer "B.Fab")
			(effects
				(font
					(size 1.27 1.27)
				)
				(justify mirror)
			)
		)
		(duplicate_pad_numbers_are_jumpers no)
		(fp_line
			(start -2.549906 -2.549906)
			(end -2.4384 -2.549906)
			(stroke
				(width 0.1524)
				(type default)
			)
			(layer "B.SilkS")
		)
		(fp_line
			(start -2.549906 -2.2352)
			(end -2.549906 -2.549906)
			(stroke
				(width 0.1524)
				(type default)
			)
			(layer "B.SilkS")
		)
		(fp_line
			(start -2.549906 -1.4986)
			(end -2.549906 -1.7526)
			(stroke
				(width 0.1524)
				(type default)
			)
			(layer "B.SilkS")
		)
		(fp_line
			(start -2.549906 -0.6858)
			(end -2.549906 -0.9144)
			(stroke
				(width 0.1524)
				(type default)
			)
			(layer "B.SilkS")
		)
		(fp_line
			(start -2.549906 0.9144)
			(end -2.549906 -0.1016)
			(stroke
				(width 0.1524)
				(type default)
			)
			(layer "B.SilkS")
		)
		(fp_line
			(start -2.549906 1.7526)
			(end -2.549906 1.4986)
			(stroke
				(width 0.1524)
				(type default)
			)
			(layer "B.SilkS")
		)
		(fp_line
			(start -2.549906 2.549906)
			(end -2.549906 2.2352)
			(stroke
				(width 0.1524)
				(type default)
			)
			(layer "B.SilkS")
		)
		(fp_line
			(start -2.4384 2.549906)
			(end -2.549906 2.549906)
			(stroke
				(width 0.1524)
				(type default)
			)
			(layer "B.SilkS")
		)
		(fp_line
			(start -2.199894 2.9464)
			(end -2.199894 3.4544)
			(stroke
				(width 0.1524)
				(type default)
			)
			(layer "B.SilkS")
		)
		(fp_line
			(start -1.800098 -3.9624)
			(end -1.800098 -2.9464)
			(stroke
				(width 0.1524)
				(type default)
			)
			(layer "B.SilkS")
		)
		(fp_line
			(start -0.199898 2.9464)
			(end -0.199898 3.9624)
			(stroke
				(width 0.1524)
				(type default)
			)
			(layer "B.SilkS")
		)
		(fp_line
			(start 0.199898 -3.4544)
			(end 0.199898 -2.9464)
			(stroke
				(width 0.1524)
				(type default)
			)
			(layer "B.SilkS")
		)
		(fp_line
			(start 1.800098 2.9464)
			(end 1.800098 3.4544)
			(stroke
				(width 0.1524)
				(type default)
			)
			(layer "B.SilkS")
		)
		(fp_line
			(start 2.199894 -3.9624)
			(end 2.199894 -2.9464)
			(stroke
				(width 0.1524)
				(type default)
			)
			(layer "B.SilkS")
		)
		(fp_line
			(start 2.4384 -2.549906)
			(end 2.549906 -2.549906)
			(stroke
				(width 0.1524)
				(type default)
			)
			(layer "B.SilkS")
		)
		(fp_line
			(start 2.549906 -2.549906)
			(end 2.549906 -2.2352)
			(stroke
				(width 0.1524)
				(type default)
			)
			(layer "B.SilkS")
		)
		(fp_line
			(start 2.549906 -1.7526)
			(end 2.549906 -1.4986)
			(stroke
				(width 0.1524)
				(type default)
			)
			(layer "B.SilkS")
		)
		(fp_line
			(start 2.549906 -0.9144)
			(end 2.549906 0.1016)
			(stroke
				(width 0.1524)
				(type default)
			)
			(layer "B.SilkS")
		)
		(fp_line
			(start 2.549906 0.6858)
			(end 2.549906 0.9144)
			(stroke
				(width 0.1524)
				(type default)
			)
			(layer "B.SilkS")
		)
		(fp_line
			(start 2.549906 1.4986)
			(end 2.549906 1.7526)
			(stroke
				(width 0.1524)
				(type default)
			)
			(layer "B.SilkS")
		)
		(fp_line
			(start 2.549906 2.2352)
			(end 2.549906 2.549906)
			(stroke
				(width 0.1524)
				(type default)
			)
			(layer "B.SilkS")
		)
		(fp_line
			(start 2.549906 2.549906)
			(end 2.4384 2.549906)
			(stroke
				(width 0.1524)
				(type default)
			)
			(layer "B.SilkS")
		)
		(fp_poly
			(pts
				(xy 3.523234 -1.491996) (xy 2.939034 -1.199896) (xy 3.523234 -0.907796)
			)
			(stroke
				(width 0)
				(type default)
			)
			(fill yes)
			(layer "B.SilkS")
		)
		(fp_line
			(start -2.549906 -2.549906)
			(end 2.549906 -2.549906)
			(stroke
				(width 0.1)
				(type default)
			)
			(layer "B.Fab")
		)
		(fp_line
			(start -2.549906 2.549906)
			(end -2.549906 -2.549906)
			(stroke
				(width 0.1)
				(type default)
			)
			(layer "B.Fab")
		)
		(fp_line
			(start -2.199894 2.9464)
			(end -2.199894 3.4544)
			(stroke
				(width 0.1)
				(type default)
			)
			(layer "B.Fab")
		)
		(fp_line
			(start -1.800098 -3.9624)
			(end -1.800098 -2.9464)
			(stroke
				(width 0.1)
				(type default)
			)
			(layer "B.Fab")
		)
		(fp_line
			(start -0.199898 2.9464)
			(end -0.199898 3.9624)
			(stroke
				(width 0.1)
				(type default)
			)
			(layer "B.Fab")
		)
		(fp_line
			(start 0.199898 -3.4544)
			(end 0.199898 -2.9464)
			(stroke
				(width 0.1)
				(type default)
			)
			(layer "B.Fab")
		)
		(fp_line
			(start 1.800098 2.9464)
			(end 1.800098 3.4544)
			(stroke
				(width 0.1)
				(type default)
			)
			(layer "B.Fab")
		)
		(fp_line
			(start 2.199894 -3.9624)
			(end 2.199894 -2.9464)
			(stroke
				(width 0.1)
				(type default)
			)
			(layer "B.Fab")
		)
		(fp_line
			(start 2.549906 -2.549906)
			(end 2.549906 2.549906)
			(stroke
				(width 0.1)
				(type default)
			)
			(layer "B.Fab")
		)
		(fp_line
			(start 2.549906 2.549906)
			(end -2.549906 2.549906)
			(stroke
				(width 0.1)
				(type default)
			)
			(layer "B.Fab")
		)
		(fp_poly
			(pts
				(xy 3.7084 -1.584706) (xy 2.939034 -1.199896) (xy 3.7084 -0.81534)
			)
			(stroke
				(width 0)
				(type default)
			)
			(fill yes)
			(layer "B.Fab")
		)
		(fp_text user "18"
			(at -3.617976 -1.080516 270)
			(unlocked yes)
			(layer "B.SilkS")
			(effects
				(font
					(size 0.635 0.4064)
					(thickness 0.1524)
				)
				(justify mirror)
			)
		)
		(fp_text user "16"
			(at -3.329432 1.2192 270)
			(unlocked yes)
			(layer "B.SilkS")
			(effects
				(font
					(size 0.635 0.4064)
					(thickness 0.1524)
				)
				(justify mirror)
			)
		)
		(fp_text user "15"
			(at -2.8956 3.126232 0)
			(unlocked yes)
			(layer "B.SilkS")
			(effects
				(font
					(size 0.635 0.4064)
					(thickness 0.1524)
				)
				(justify mirror)
			)
		)
		(fp_text user "19"
			(at -2.8448 -3.096768 0)
			(unlocked yes)
			(layer "B.SilkS")
			(effects
				(font
					(size 0.635 0.4064)
					(thickness 0.1524)
				)
				(justify mirror)
			)
		)
		(fp_text user "4"
			(at 2.6416 3.151632 0)
			(unlocked yes)
			(layer "B.SilkS")
			(effects
				(font
					(size 0.635 0.4064)
					(thickness 0.1524)
				)
				(justify mirror)
			)
		)
		(fp_text user "30"
			(at 2.9464 -3.045968 0)
			(unlocked yes)
			(layer "B.SilkS")
			(effects
				(font
					(size 0.635 0.4064)
					(thickness 0.1524)
				)
				(justify mirror)
			)
		)
		(fp_text user "3"
			(at 3.299968 1.1938 270)
			(unlocked yes)
			(layer "B.SilkS")
			(effects
				(font
					(size 0.635 0.4064)
					(thickness 0.1524)
				)
				(justify mirror)
			)
		)
		(fp_text user "16"
			(at -3.329432 1.2192 270)
			(unlocked yes)
			(layer "B.Fab")
			(effects
				(font
					(size 0.635 0.4064)
					(thickness 0.1524)
				)
				(justify mirror)
			)
		)
		(fp_text user "18"
			(at -3.304032 -1.2192 270)
			(unlocked yes)
			(layer "B.Fab")
			(effects
				(font
					(size 0.635 0.4064)
					(thickness 0.1524)
				)
				(justify mirror)
			)
		)
		(fp_text user "15"
			(at -2.8956 3.126232 0)
			(unlocked yes)
			(layer "B.Fab")
			(effects
				(font
					(size 0.635 0.4064)
					(thickness 0.1524)
				)
				(justify mirror)
			)
		)
		(fp_text user "19"
			(at -2.8448 -3.096768 0)
			(unlocked yes)
			(layer "B.Fab")
			(effects
				(font
					(size 0.635 0.4064)
					(thickness 0.1524)
				)
				(justify mirror)
			)
		)
		(fp_text user "4"
			(at 2.6416 3.151632 0)
			(unlocked yes)
			(layer "B.Fab")
			(effects
				(font
					(size 0.635 0.4064)
					(thickness 0.1524)
				)
				(justify mirror)
			)
		)
		(fp_text user "30"
			(at 2.9464 -3.045968 0)
			(unlocked yes)
			(layer "B.Fab")
			(effects
				(font
					(size 0.635 0.4064)
					(thickness 0.1524)
				)
				(justify mirror)
			)
		)
		(fp_text user "3"
			(at 3.299968 1.1938 270)
			(unlocked yes)
			(layer "B.Fab")
			(effects
				(font
					(size 0.635 0.4064)
					(thickness 0.1524)
				)
				(justify mirror)
			)
		)
		(pad "1" smd circle
			(at 1.599946 -1.199896 270)
			(size 0 0)
			(layers "B.Cu" "B.Mask" "B.Paste")
			(net "P52V_HSC")
		)
		(pad "2" smd rect
			(at 1.549908 0.40005 90)
			(size 0.3048 2.5146)
			(layers "B.Cu" "B.Mask" "B.Paste")
			(net "P52V_HSC")
		)
		(pad "3" smd rect
			(at 1.549908 1.199896 90)
			(size 0.3048 2.5146)
			(layers "B.Cu" "B.Mask" "B.Paste")
			(net "P52V_FAN_6")
		)
		(pad "4" smd circle
			(at 2.199894 2.350008)
			(size 0 0)
			(layers "B.Cu" "B.Mask" "B.Paste")
			(net "P52V_FAN_6")
		)
		(pad "5" smd rect
			(at 1.800098 2.350008 180)
			(size 0.1778 0.9144)
			(layers "B.Cu" "B.Mask" "B.Paste")
			(net "P52V_FAN_6")
		)
		(pad "6" smd rect
			(at 1.400048 2.350008 180)
			(size 0.1778 0.9144)
			(layers "B.Cu" "B.Mask" "B.Paste")
			(net "P52V_FAN_6")
		)
		(pad "7" smd rect
			(at 0.999998 2.350008 180)
			(size 0.1778 0.9144)
			(layers "B.Cu" "B.Mask" "B.Paste")
			(net "P52V_FAN_6")
		)
		(pad "8" smd rect
			(at 0.599948 2.350008 180)
			(size 0.1778 0.9144)
			(layers "B.Cu" "B.Mask" "B.Paste")
			(net "P52V_FAN_6")
		)
		(pad "9" smd rect
			(at 0.199898 2.350008 180)
			(size 0.1778 0.9144)
			(layers "B.Cu" "B.Mask" "B.Paste")
			(net "P52V_FAN_6")
		)
		(pad "10" smd rect
			(at -0.199898 2.350008 180)
			(size 0.1778 0.9144)
			(layers "B.Cu" "B.Mask" "B.Paste")
			(net "P52V_FAN_6")
		)
		(pad "11" smd rect
			(at -0.599948 2.350008 180)
			(size 0.1778 0.9144)
			(layers "B.Cu" "B.Mask" "B.Paste")
			(net "P52V_FAN_6")
		)
		(pad "12" smd rect
			(at -0.999998 2.350008 180)
			(size 0.1778 0.9144)
			(layers "B.Cu" "B.Mask" "B.Paste")
			(net "P52V_FAN_6")
		)
		(pad "13" smd rect
			(at -1.400048 2.350008 180)
			(size 0.1778 0.9144)
			(layers "B.Cu" "B.Mask" "B.Paste")
			(net "P52V_FAN_6")
		)
		(pad "14" smd rect
			(at -1.800098 2.350008 180)
			(size 0.1778 0.9144)
			(layers "B.Cu" "B.Mask" "B.Paste")
			(net "P52V_FAN_6")
		)
		(pad "15" smd circle
			(at -2.199894 2.350008)
			(size 0 0)
			(layers "B.Cu" "B.Mask" "B.Paste")
			(net "P52V_FAN_6")
		)
		(pad "16" smd rect
			(at -1.549908 1.199896 90)
			(size 0.3048 2.5146)
			(layers "B.Cu" "B.Mask" "B.Paste")
			(net "P52V_FAN_6")
		)
		(pad "17" smd rect
			(at -1.549908 -0.40005 90)
			(size 0.3048 2.5146)
			(layers "B.Cu" "B.Mask" "B.Paste")
			(net "P52V_FAN_6")
		)
		(pad "18" smd rect
			(at -1.549908 -1.199896 90)
			(size 0.3048 2.5146)
			(layers "B.Cu" "B.Mask" "B.Paste")
			(net "P52V_HSC")
		)
		(pad "19" smd circle
			(at -2.199894 -2.350008 180)
			(size 0 0)
			(layers "B.Cu" "B.Mask" "B.Paste")
			(net "FAN_6_CS")
		)
		(pad "20" smd rect
			(at -1.800098 -2.350008 180)
			(size 0.1778 0.9144)
			(layers "B.Cu" "B.Mask" "B.Paste")
			(net "FAN_6_IMON")
		)
		(pad "21" smd rect
			(at -1.400048 -2.350008 180)
			(size 0.1778 0.9144)
			(layers "B.Cu" "B.Mask" "B.Paste")
			(net "FAN_6_SS")
		)
		(pad "22" smd rect
			(at -0.999998 -2.350008 180)
			(size 0.1778 0.9144)
			(layers "B.Cu" "B.Mask" "B.Paste")
			(net "FAN_6_FAULT")
		)
		(pad "23" smd rect
			(at -0.599948 -2.350008 180)
			(size 0.1778 0.9144)
			(layers "B.Cu" "B.Mask" "B.Paste")
			(net "FAN_6_TIMER")
		)
		(pad "24" smd rect
			(at -0.199898 -2.350008 180)
			(size 0.1778 0.9144)
			(layers "B.Cu" "B.Mask" "B.Paste")
			(net "FAN_6_CLREF")
		)
		(pad "25" smd rect
			(at 0.199898 -2.350008 180)
			(size 0.1778 0.9144)
			(layers "B.Cu" "B.Mask" "B.Paste")
			(net "GND")
		)
		(pad "26" smd rect
			(at 0.599948 -2.350008 180)
			(size 0.1778 0.9144)
			(layers "B.Cu" "B.Mask" "B.Paste")
			(net "FAN_6_ON")
		)
		(pad "27" smd rect
			(at 0.999998 -2.350008 180)
			(size 0.1778 0.9144)
			(layers "B.Cu" "B.Mask" "B.Paste")
			(net "FAN_6_P3V_R")
		)
		(pad "28" smd rect
			(at 1.400048 -2.350008 180)
			(size 0.1778 0.9144)
			(layers "B.Cu" "B.Mask" "B.Paste")
			(net "FAN_6_P5V")
		)
		(pad "29" smd rect
			(at 1.800098 -2.350008 180)
			(size 0.1778 0.9144)
			(layers "B.Cu" "B.Mask" "B.Paste")
			(net "FAN_6_TEMP")
		)
		(pad "30" smd circle
			(at 2.199894 -2.350008 180)
			(size 0 0)
			(layers "B.Cu" "B.Mask" "B.Paste")
			(net "FAN_6_MODE")
		)
	)
	(footprint ""
		(layer "B.Cu")
		(at 2.794 -64.837056 90)
		(property "Reference" "PR54"
			(at 0 0 90)
			(layer "B.SilkS")
			(hide yes)
			(effects
				(font
					(size 1.27 1.27)
				)
				(justify mirror)
			)
		)
		(property "Value" ""
			(at 0 0 90)
			(layer "B.Fab")
			(effects
				(font
					(size 1.27 1.27)
				)
				(justify mirror)
			)
		)
		(duplicate_pad_numbers_are_jumpers no)
		(fp_line
			(start 0.7874 -0.4064)
			(end -0.7874 -0.4064)
			(stroke
				(width 0.1524)
				(type default)
			)
			(layer "B.SilkS")
		)
		(fp_line
			(start -0.7874 -0.4064)
			(end -0.7874 0.4064)
			(stroke
				(width 0.1524)
				(type default)
			)
			(layer "B.SilkS")
		)
		(fp_line
			(start 0.7874 0.4064)
			(end 0.7874 -0.4064)
			(stroke
				(width 0.1524)
				(type default)
			)
			(layer "B.SilkS")
		)
		(fp_line
			(start -0.7874 0.4064)
			(end 0.7874 0.4064)
			(stroke
				(width 0.1524)
				(type default)
			)
			(layer "B.SilkS")
		)
		(fp_line
			(start 0.67945 -0.305054)
			(end 0.12065 -0.305054)
			(stroke
				(width 0.1)
				(type default)
			)
			(layer "B.Fab")
		)
		(fp_line
			(start 0.12065 -0.305054)
			(end 0.12065 -0.2794)
			(stroke
				(width 0.1)
				(type default)
			)
			(layer "B.Fab")
		)
		(fp_line
			(start -0.12065 -0.3048)
			(end -0.67945 -0.3048)
			(stroke
				(width 0.1)
				(type default)
			)
			(layer "B.Fab")
		)
		(fp_line
			(start -0.67945 -0.3048)
			(end -0.67945 0.3048)
			(stroke
				(width 0.1)
				(type default)
			)
			(layer "B.Fab")
		)
		(fp_line
			(start 0.12065 -0.2794)
			(end -0.12065 -0.2794)
			(stroke
				(width 0.1)
				(type default)
			)
			(layer "B.Fab")
		)
		(fp_line
			(start -0.12065 -0.2794)
			(end -0.12065 -0.3048)
			(stroke
				(width 0.1)
				(type default)
			)
			(layer "B.Fab")
		)
		(fp_line
			(start 0.12065 0.2794)
			(end 0.12065 0.3048)
			(stroke
				(width 0.1)
				(type default)
			)
			(layer "B.Fab")
		)
		(fp_line
			(start -0.120396 0.2794)
			(end 0.12065 0.2794)
			(stroke
				(width 0.1)
				(type default)
			)
			(layer "B.Fab")
		)
		(fp_line
			(start 0.67945 0.3048)
			(end 0.67945 -0.305054)
			(stroke
				(width 0.1)
				(type default)
			)
			(layer "B.Fab")
		)
		(fp_line
			(start 0.12065 0.3048)
			(end 0.67945 0.3048)
			(stroke
				(width 0.1)
				(type default)
			)
			(layer "B.Fab")
		)
		(fp_line
			(start -0.120396 0.3048)
			(end -0.120396 0.2794)
			(stroke
				(width 0.1)
				(type default)
			)
			(layer "B.Fab")
		)
		(fp_line
			(start -0.67945 0.3048)
			(end -0.120396 0.3048)
			(stroke
				(width 0.1)
				(type default)
			)
			(layer "B.Fab")
		)
		(pad "1" smd circle
			(at 0.40005 0 270)
			(size 0 0)
			(layers "B.Cu" "B.Mask" "B.Paste")
			(net "GND")
		)
		(pad "2" smd circle
			(at -0.40005 0 270)
			(size 0 0)
			(layers "B.Cu" "B.Mask" "B.Paste")
			(net "FAN_4_IMON")
		)
	)
)
